(kicad_pcb
	(version 20241229)
	(generator "pcbnew")
	(generator_version "9.0")
	(general
		(thickness 1.61)
		(legacy_teardrops no)
	)
	(paper "A3")
	(title_block
		(title "RDIMM DDR5 Tester")
		(date "2026-05-21")
		(rev "2.2.0")
		(company "Antmicro")
		(comment 9 "footprints 120-123 of 796")
	)
	(layers
		(0 "F.Cu" signal)
		(4 "In1.Cu" power)
		(6 "In2.Cu" mixed)
		(8 "In3.Cu" power)
		(10 "In4.Cu" mixed)
		(12 "In5.Cu" power)
		(14 "In6.Cu" mixed)
		(16 "In7.Cu" power)
		(18 "In8.Cu" power)
		(20 "In9.Cu" mixed)
		(22 "In10.Cu" power)
		(2 "B.Cu" signal)
		(9 "F.Adhes" user "F.Adhesive")
		(11 "B.Adhes" user "B.Adhesive")
		(13 "F.Paste" user)
		(15 "B.Paste" user)
		(5 "F.SilkS" user "F.Silkscreen")
		(7 "B.SilkS" user "B.Silkscreen")
		(1 "F.Mask" user)
		(3 "B.Mask" user)
		(17 "Dwgs.User" user "User.Drawings")
		(19 "Cmts.User" user "User.Comments")
		(21 "Eco1.User" user "User.Eco1")
		(23 "Eco2.User" user "User.Eco2")
		(25 "Edge.Cuts" user)
		(27 "Margin" user)
		(31 "F.CrtYd" user "F.Courtyard")
		(29 "B.CrtYd" user "B.Courtyard")
		(35 "F.Fab" user)
		(33 "B.Fab" user)
	)
	(footprint "antmicro-footprints:C_0402_1005Metric"
		(layer "F.Cu")
		(at 139.624499 169.099 -90)
		(descr "Capacitor SMD 0402")
		(tags "capacitor SMD 0402")
		(property "Reference" "C121"
			(at -1.199 -2.725501 90)
			(layer "F.SilkS")
			(effects
				(font
					(size 0.7 0.7)
					(thickness 0.15)
				)
				(justify right bottom)
			)
		)
		(property "Value" "C_100n_0402"
			(at -1.022927 2.155213 90)
			(layer "F.Fab")
			(effects
				(font
					(size 0.7 0.7)
					(thickness 0.15)
				)
				(justify right bottom)
			)
		)
		(property "Datasheet" "https://www.murata.com/products/productdetail?partno=GRM155R61H104KE14%23"
			(at 0 0 270)
			(layer "F.Fab")
			(hide yes)
			(effects
				(font
					(size 1.27 1.27)
					(thickness 0.15)
				)
			)
		)
		(property "MPN" "GRM155R61H104KE14D"
			(at 0 0 270)
			(unlocked yes)
			(layer "F.Fab")
			(hide yes)
			(effects
				(font
					(size 1 1)
					(thickness 0.15)
				)
			)
		)
		(property "Manufacturer" "Murata"
			(at 0 0 270)
			(unlocked yes)
			(layer "F.Fab")
			(hide yes)
			(effects
				(font
					(size 1 1)
					(thickness 0.15)
				)
			)
		)
		(property "License" "Apache-2.0"
			(at 0 0 270)
			(unlocked yes)
			(layer "F.Fab")
			(hide yes)
			(effects
				(font
					(size 1 1)
					(thickness 0.15)
				)
			)
		)
		(property "Author" "Antmicro"
			(at 0 0 270)
			(unlocked yes)
			(layer "F.Fab")
			(hide yes)
			(effects
				(font
					(size 1 1)
					(thickness 0.15)
				)
			)
		)
		(property "Val" "100n"
			(at 0 0 270)
			(unlocked yes)
			(layer "F.Fab")
			(hide yes)
			(effects
				(font
					(size 1 1)
					(thickness 0.15)
				)
			)
		)
		(property "Voltage" "50V"
			(at 0 0 270)
			(unlocked yes)
			(layer "F.Fab")
			(hide yes)
			(effects
				(font
					(size 1 1)
					(thickness 0.15)
				)
			)
		)
		(property "Dielectric" "X5R"
			(at 0 0 270)
			(unlocked yes)
			(layer "F.Fab")
			(hide yes)
			(effects
				(font
					(size 1 1)
					(thickness 0.15)
				)
			)
		)
		(sheetname "/Debug FTDI + VNA/")
		(sheetfile "debug-ftdi.kicad_sch")
		(attr smd)
		(fp_rect
			(start -0.925 -0.47)
			(end 0.925 0.47)
			(stroke
				(width 0.05)
				(type default)
			)
			(fill no)
			(layer "F.CrtYd")
		)
		(fp_line
			(start -0.494 0.248)
			(end -0.494 -0.25)
			(stroke
				(width 0.15)
				(type solid)
			)
			(layer "F.Fab")
		)
		(fp_line
			(start 0.504 0.248)
			(end -0.494 0.248)
			(stroke
				(width 0.15)
				(type solid)
			)
			(layer "F.Fab")
		)
		(fp_line
			(start -0.494 -0.25)
			(end 0.504 -0.25)
			(stroke
				(width 0.15)
				(type solid)
			)
			(layer "F.Fab")
		)
		(fp_line
			(start 0.504 -0.25)
			(end 0.504 0.248)
			(stroke
				(width 0.15)
				(type solid)
			)
			(layer "F.Fab")
		)
		(fp_text user "Author: Antmicro"
			(at -0.939 3.399 270)
			(layer "F.Fab")
			(effects
				(font
					(size 0.7 0.7)
					(thickness 0.15)
				)
				(justify left bottom)
			)
		)
		(fp_text user "License: Apache-2.0"
			(at -0.939 5.799 270)
			(layer "F.Fab")
			(effects
				(font
					(size 0.7 0.7)
					(thickness 0.15)
				)
				(justify left bottom)
			)
		)
		(fp_text user "${REFERENCE}"
			(at -0.939 4.599 270)
			(layer "F.Fab")
			(effects
				(font
					(size 0.7 0.7)
					(thickness 0.15)
				)
				(justify left bottom)
			)
		)
		(pad "1" smd roundrect
			(at -0.48 0 270)
			(size 0.59 0.64)
			(layers "F.Cu" "F.Mask" "F.Paste")
			(roundrect_rratio 0.25)
			(net 1 "GND")
			(pintype "passive")
		)
		(pad "2" smd roundrect
			(at 0.48 0 270)
			(size 0.59 0.64)
			(layers "F.Cu" "F.Mask" "F.Paste")
			(roundrect_rratio 0.25)
			(net 6 "/Debug FTDI + VNA/FTDI_3V3")
			(pintype "passive")
		)
	)
	(footprint "antmicro-footprints:C_0402_1005Metric"
		(layer "F.Cu")
		(at 249.8 186.449 -90)
		(descr "Capacitor SMD 0402")
		(tags "capacitor SMD 0402")
		(property "Reference" "C322"
			(at -0.975 -1.45 90)
			(layer "F.SilkS")
			(effects
				(font
					(size 0.7 0.7)
					(thickness 0.15)
				)
				(justify right bottom)
			)
		)
		(property "Value" "C_100n_0402"
			(at -1.022927 2.155213 90)
			(layer "F.Fab")
			(effects
				(font
					(size 0.7 0.7)
					(thickness 0.15)
				)
				(justify right bottom)
			)
		)
		(property "Datasheet" "https://www.murata.com/products/productdetail?partno=GRM155R61H104KE14%23"
			(at 0 0 270)
			(layer "F.Fab")
			(hide yes)
			(effects
				(font
					(size 1.27 1.27)
					(thickness 0.15)
				)
			)
		)
		(property "Manufacturer" "Murata"
			(at 0 0 270)
			(unlocked yes)
			(layer "F.Fab")
			(hide yes)
			(effects
				(font
					(size 1 1)
					(thickness 0.15)
				)
			)
		)
		(property "MPN" "GRM155R61H104KE14D"
			(at 0 0 270)
			(unlocked yes)
			(layer "F.Fab")
			(hide yes)
			(effects
				(font
					(size 1 1)
					(thickness 0.15)
				)
			)
		)
		(property "Val" "100n"
			(at 0 0 270)
			(unlocked yes)
			(layer "F.Fab")
			(hide yes)
			(effects
				(font
					(size 1 1)
					(thickness 0.15)
				)
			)
		)
		(property "License" "Apache-2.0"
			(at 0 0 270)
			(unlocked yes)
			(layer "F.Fab")
			(hide yes)
			(effects
				(font
					(size 1 1)
					(thickness 0.15)
				)
			)
		)
		(property "Author" "Antmicro"
			(at 0 0 270)
			(unlocked yes)
			(layer "F.Fab")
			(hide yes)
			(effects
				(font
					(size 1 1)
					(thickness 0.15)
				)
			)
		)
		(property "Voltage" "50V"
			(at 0 0 270)
			(unlocked yes)
			(layer "F.Fab")
			(hide yes)
			(effects
				(font
					(size 1 1)
					(thickness 0.15)
				)
			)
		)
		(property "Dielectric" "X5R"
			(at 0 0 270)
			(unlocked yes)
			(layer "F.Fab")
			(hide yes)
			(effects
				(font
					(size 1 1)
					(thickness 0.15)
				)
			)
		)
		(sheetname "/I^{2}C + I3C/")
		(sheetfile "i2c.kicad_sch")
		(attr smd)
		(fp_rect
			(start -0.925 -0.47)
			(end 0.925 0.47)
			(stroke
				(width 0.05)
				(type default)
			)
			(fill no)
			(layer "F.CrtYd")
		)
		(fp_line
			(start -0.494 0.248)
			(end -0.494 -0.25)
			(stroke
				(width 0.15)
				(type solid)
			)
			(layer "F.Fab")
		)
		(fp_line
			(start 0.504 0.248)
			(end -0.494 0.248)
			(stroke
				(width 0.15)
				(type solid)
			)
			(layer "F.Fab")
		)
		(fp_line
			(start -0.494 -0.25)
			(end 0.504 -0.25)
			(stroke
				(width 0.15)
				(type solid)
			)
			(layer "F.Fab")
		)
		(fp_line
			(start 0.504 -0.25)
			(end 0.504 0.248)
			(stroke
				(width 0.15)
				(type solid)
			)
			(layer "F.Fab")
		)
		(fp_text user "${REFERENCE}"
			(at -0.939 4.599 270)
			(layer "F.Fab")
			(effects
				(font
					(size 0.7 0.7)
					(thickness 0.15)
				)
				(justify left bottom)
			)
		)
		(fp_text user "Author: Antmicro"
			(at -0.939 3.399 270)
			(layer "F.Fab")
			(effects
				(font
					(size 0.7 0.7)
					(thickness 0.15)
				)
				(justify left bottom)
			)
		)
		(fp_text user "License: Apache-2.0"
			(at -0.939 5.799 270)
			(layer "F.Fab")
			(effects
				(font
					(size 0.7 0.7)
					(thickness 0.15)
				)
				(justify left bottom)
			)
		)
		(pad "1" smd roundrect
			(at -0.48 0 270)
			(size 0.59 0.64)
			(layers "F.Cu" "F.Mask" "F.Paste")
			(roundrect_rratio 0.25)
			(net 775 "Net-(Q24-S)")
			(pintype "passive")
		)
		(pad "2" smd roundrect
			(at 0.48 0 270)
			(size 0.59 0.64)
			(layers "F.Cu" "F.Mask" "F.Paste")
			(roundrect_rratio 0.25)
			(net 1 "GND")
			(pintype "passive")
		)
	)
	(footprint "antmicro-footprints:R_0402_1005Metric"
		(layer "F.Cu")
		(at 260.5055 151.921 90)
		(descr "Resistor SMD 0402")
		(tags "resistor SMD 0402")
		(property "Reference" "R166"
			(at -1.379 1.8445 90)
			(layer "F.SilkS")
			(effects
				(font
					(size 0.7 0.7)
					(thickness 0.15)
				)
				(justify left bottom)
			)
		)
		(property "Value" "R_0R_0402"
			(at -1.011843 1.772047 90)
			(layer "F.Fab")
			(effects
				(font
					(size 0.7 0.7)
					(thickness 0.15)
				)
				(justify left bottom)
			)
		)
		(property "Datasheet" "https://industrial.panasonic.com/cdbs/www-data/pdf/RDA0000/AOA0000C301.pdf"
			(at 0 0 90)
			(layer "F.Fab")
			(hide yes)
			(effects
				(font
					(size 1.27 1.27)
					(thickness 0.15)
				)
			)
		)
		(property "Manufacturer" "Panasonic"
			(at 0 0 90)
			(unlocked yes)
			(layer "F.Fab")
			(hide yes)
			(effects
				(font
					(size 1 1)
					(thickness 0.15)
				)
			)
		)
		(property "MPN" "ERJ2GE0R00X"
			(at 0 0 90)
			(unlocked yes)
			(layer "F.Fab")
			(hide yes)
			(effects
				(font
					(size 1 1)
					(thickness 0.15)
				)
			)
		)
		(property "Val" "0R"
			(at 0 0 90)
			(unlocked yes)
			(layer "F.Fab")
			(hide yes)
			(effects
				(font
					(size 1 1)
					(thickness 0.15)
				)
			)
		)
		(property "License" "Apache-2.0"
			(at 0 0 90)
			(unlocked yes)
			(layer "F.Fab")
			(hide yes)
			(effects
				(font
					(size 1 1)
					(thickness 0.15)
				)
			)
		)
		(property "Author" "Antmicro"
			(at 0 0 90)
			(unlocked yes)
			(layer "F.Fab")
			(hide yes)
			(effects
				(font
					(size 1 1)
					(thickness 0.15)
				)
			)
		)
		(property "Tolerance" "~"
			(at 0 0 90)
			(unlocked yes)
			(layer "F.Fab")
			(hide yes)
			(effects
				(font
					(size 1 1)
					(thickness 0.15)
				)
			)
		)
		(property "Current" "1A"
			(at 0 0 90)
			(unlocked yes)
			(layer "F.Fab")
			(hide yes)
			(effects
				(font
					(size 1 1)
					(thickness 0.15)
				)
			)
		)
		(sheetname "/Supply/DC-DC IO/")
		(sheetfile "dc-dc-io.kicad_sch")
		(attr smd)
		(fp_rect
			(start -0.925 -0.47)
			(end 0.925 0.47)
			(stroke
				(width 0.05)
				(type default)
			)
			(fill no)
			(layer "F.CrtYd")
		)
		(fp_rect
			(start -0.5 -0.25)
			(end 0.5 0.25)
			(stroke
				(width 0.15)
				(type solid)
			)
			(fill no)
			(layer "F.Fab")
		)
		(fp_text user "${REFERENCE}"
			(at -0.95 3.168 90)
			(layer "F.Fab")
			(effects
				(font
					(size 0.7 0.7)
					(thickness 0.15)
				)
				(justify left bottom)
			)
		)
		(fp_text user "License: Apache-2.0"
			(at -0.95 5.169 90)
			(layer "F.Fab")
			(effects
				(font
					(size 0.7 0.7)
					(thickness 0.15)
				)
				(justify left bottom)
			)
		)
		(fp_text user "Author: Antmicro"
			(at -0.95 4.169 90)
			(layer "F.Fab")
			(effects
				(font
					(size 0.7 0.7)
					(thickness 0.15)
				)
				(justify left bottom)
			)
		)
		(pad "1" smd roundrect
			(at -0.48 0 90)
			(size 0.59 0.64)
			(layers "F.Cu" "F.Mask" "F.Paste")
			(roundrect_rratio 0.25)
			(net 718 "/Supply/DC-DC IO/FB7")
			(pintype "passive")
		)
		(pad "2" smd roundrect
			(at 0.48 0 90)
			(size 0.59 0.64)
			(layers "F.Cu" "F.Mask" "F.Paste")
			(roundrect_rratio 0.25)
			(net 158 "/Supply/DC-DC IO/VDDQ_local")
			(pintype "passive")
		)
	)
	(footprint "antmicro-footprints:SOT-23-3"
		(layer "F.Cu")
		(at 207.29 151 -90)
		(property "Reference" "U30"
			(at -1.85 0.79 180)
			(layer "F.SilkS")
			(effects
				(font
					(size 0.7 0.7)
					(thickness 0.15)
				)
				(justify right bottom)
			)
		)
		(property "Value" "REF3012AIDBZT"
			(at -1.9 2.7 90)
			(layer "F.Fab")
			(effects
				(font
					(size 0.7 0.7)
					(thickness 0.15)
				)
				(justify right bottom)
			)
		)
		(property "Datasheet" "https://www.ti.com/lit/gpn/REF3012"
			(at 0 0 270)
			(layer "F.Fab")
			(hide yes)
			(effects
				(font
					(size 1.27 1.27)
					(thickness 0.15)
				)
			)
		)
		(property "MPN" "REF3012AIDBZT"
			(at 0 0 270)
			(unlocked yes)
			(layer "F.Fab")
			(hide yes)
			(effects
				(font
					(size 1 1)
					(thickness 0.15)
				)
			)
		)
		(property "Manufacturer" "Texas Instruments"
			(at 0 0 270)
			(unlocked yes)
			(layer "F.Fab")
			(hide yes)
			(effects
				(font
					(size 1 1)
					(thickness 0.15)
				)
			)
		)
		(property "Author" "Antmicro"
			(at 0 0 270)
			(unlocked yes)
			(layer "F.Fab")
			(hide yes)
			(effects
				(font
					(size 1 1)
					(thickness 0.15)
				)
			)
		)
		(property "License" "Apache-2.0"
			(at 0 0 270)
			(unlocked yes)
			(layer "F.Fab")
			(hide yes)
			(effects
				(font
					(size 1 1)
					(thickness 0.15)
				)
			)
		)
		(sheetname "/FPGA Config/")
		(sheetfile "fpga-config.kicad_sch")
		(attr smd)
		(fp_line
			(start -0.7 1.5)
			(end -0.7 1.35)
			(stroke
				(width 0.15)
				(type solid)
			)
			(layer "F.SilkS")
		)
		(fp_line
			(start 0.7 1.5)
			(end -0.7 1.5)
			(stroke
				(width 0.15)
				(type solid)
			)
			(layer "F.SilkS")
		)
		(fp_line
			(start 0.7 0.4)
			(end 0.7 1.5)
			(stroke
				(width 0.15)
				(type solid)
			)
			(layer "F.SilkS")
		)
		(fp_line
			(start 0.7 -0.4)
			(end 0.7 -1.5)
			(stroke
				(width 0.15)
				(type solid)
			)
			(layer "F.SilkS")
		)
		(fp_line
			(start -1.45 -1.35)
			(end -0.85 -1.35)
			(stroke
				(width 0.15)
				(type solid)
			)
			(layer "F.SilkS")
		)
		(fp_line
			(start -0.85 -1.35)
			(end -0.7 -1.5)
			(stroke
				(width 0.15)
				(type solid)
			)
			(layer "F.SilkS")
		)
		(fp_line
			(start 0.7 -1.5)
			(end -0.7 -1.5)
			(stroke
				(width 0.15)
				(type solid)
			)
			(layer "F.SilkS")
		)
		(fp_line
			(start -0.85 1.65)
			(end -0.85 1.4)
			(stroke
				(width 0.05)
				(type solid)
			)
			(layer "F.CrtYd")
		)
		(fp_line
			(start 0.85 1.65)
			(end -0.85 1.65)
			(stroke
				(width 0.05)
				(type solid)
			)
			(layer "F.CrtYd")
		)
		(fp_line
			(start -1.75 1.4)
			(end -1.75 0.5)
			(stroke
				(width 0.05)
				(type solid)
			)
			(layer "F.CrtYd")
		)
		(fp_line
			(start -0.85 1.4)
			(end -1.75 1.4)
			(stroke
				(width 0.05)
				(type solid)
			)
			(layer "F.CrtYd")
		)
		(fp_line
			(start -1.75 0.5)
			(end -0.85 0.5)
			(stroke
				(width 0.05)
				(type solid)
			)
			(layer "F.CrtYd")
		)
		(fp_line
			(start -0.85 0.5)
			(end -0.85 -0.5)
			(stroke
				(width 0.05)
				(type solid)
			)
			(layer "F.CrtYd")
		)
		(fp_line
			(start 0.85 0.45)
			(end 0.85 1.65)
			(stroke
				(width 0.05)
				(type solid)
			)
			(layer "F.CrtYd")
		)
		(fp_line
			(start 1.75 0.45)
			(end 0.85 0.45)
			(stroke
				(width 0.05)
				(type solid)
			)
			(layer "F.CrtYd")
		)
		(fp_line
			(start 0.825 -0.45)
			(end 1.75 -0.45)
			(stroke
				(width 0.05)
				(type solid)
			)
			(layer "F.CrtYd")
		)
		(fp_line
			(start 1.75 -0.45)
			(end 1.75 0.45)
			(stroke
				(width 0.05)
				(type solid)
			)
			(layer "F.CrtYd")
		)
		(fp_line
			(start -1.75 -0.5)
			(end -1.75 -1.4)
			(stroke
				(width 0.05)
				(type solid)
			)
			(layer "F.CrtYd")
		)
		(fp_line
			(start -0.85 -0.5)
			(end -1.75 -0.5)
			(stroke
				(width 0.05)
				(type solid)
			)
			(layer "F.CrtYd")
		)
		(fp_line
			(start -0.9 -1.4)
			(end -1.75 -1.4)
			(stroke
				(width 0.05)
				(type solid)
			)
			(layer "F.CrtYd")
		)
		(fp_line
			(start -0.9 -1.6)
			(end -0.9 -1.4)
			(stroke
				(width 0.05)
				(type solid)
			)
			(layer "F.CrtYd")
		)
		(fp_line
			(start -0.9 -1.6)
			(end 0.825 -1.6)
			(stroke
				(width 0.05)
				(type solid)
			)
			(layer "F.CrtYd")
		)
		(fp_line
			(start 0.825 -1.6)
			(end 0.825 -0.45)
			(stroke
				(width 0.05)
				(type solid)
			)
			(layer "F.CrtYd")
		)
		(fp_line
			(start -0.712 1.519)
			(end 0.688 1.519)
			(stroke
				(width 0.15)
				(type solid)
			)
			(layer "F.Fab")
		)
		(fp_line
			(start 0.688 1.519)
			(end 0.688 -1.52)
			(stroke
				(width 0.15)
				(type solid)
			)
			(layer "F.Fab")
		)
		(fp_line
			(start -0.712 -1.325)
			(end -0.712 1.523)
			(stroke
				(width 0.15)
				(type solid)
			)
			(layer "F.Fab")
		)
		(fp_line
			(start -0.437 -1.526)
			(end -0.712 -1.325)
			(stroke
				(width 0.15)
				(type solid)
			)
			(layer "F.Fab")
		)
		(fp_line
			(start -0.437 -1.526)
			(end 0.688 -1.526)
			(stroke
				(width 0.15)
				(type solid)
			)
			(layer "F.Fab")
		)
		(fp_text user "License: Apache-2.0"
			(at -1.8 6.8 270)
			(layer "F.Fab")
			(effects
				(font
					(size 0.7 0.7)
					(thickness 0.15)
				)
				(justify left bottom)
			)
		)
		(fp_text user "Author: Antmicro"
			(at -1.837 5.3 270)
			(layer "F.Fab")
			(effects
				(font
					(size 0.7 0.7)
					(thickness 0.15)
				)
				(justify left bottom)
			)
		)
		(fp_text user "${REFERENCE}"
			(at -1.837 4 270)
			(layer "F.Fab")
			(effects
				(font
					(size 0.7 0.7)
					(thickness 0.15)
				)
				(justify left bottom)
			)
		)
		(pad "1" smd roundrect
			(at -1.1 -0.951 270)
			(size 1 0.6)
			(layers "F.Cu" "F.Mask" "F.Paste")
			(roundrect_rratio 0.15)
			(net 797 "+1V8")
			(pinfunction "IN")
			(pintype "power_in")
		)
		(pad "2" smd roundrect
			(at -1.1 0.949 270)
			(size 1 0.6)
			(layers "F.Cu" "F.Mask" "F.Paste")
			(roundrect_rratio 0.15)
			(net 160 "Net-(U30-OUT)")
			(pinfunction "OUT")
			(pintype "output")
		)
		(pad "3" smd roundrect
			(at 1.1 -0.0005 270)
			(size 1 0.6)
			(layers "F.Cu" "F.Mask" "F.Paste")
			(roundrect_rratio 0.15)
			(net 1 "GND")
			(pinfunction "GND")
			(pintype "passive")
		)
	)
)
